# BASEBOARD_FAB2 (Tioga Pass) — schematic netlist excerpt (pin names and nets, part order shuffled) for the footprints in the layout excerpt that follows; sources: Cadence DE-HDL packaged netlist, KiCad conversion of Wiwynn_Tioga_Pass_MB.brd

R8G23  RES  4.75K 1% CHIP  pkg 0402  page 189 : A = JTAG_TCK_R ; B = GND
C1W16  CAP  1000PF 50V 10% X7R  pkg 0402LF  page 199 : A = A_HSC_TEMP ; B = GND
R3B5  RES  0.0 5% CHIP  pkg 0402  page 55 : A = SVID_CLK0_CPU1 ; B = SVID_CLK0_CPU1_R

(kicad_pcb
	(version 20260206)
	(generator "pcbnew")
	(generator_version "10.0")
	(general
		(thickness 1.6)
		(legacy_teardrops no)
	)
	(paper "A4")
	(title_block
		(title "Wiwynn_Tioga_Pass_MB.brd")
		(comment 1 "Tioga Pass / footprints 1607-1609 of 4770")
	)
	(layers
		(0 "F.Cu" signal "TOP")
		(4 "In1.Cu" signal "L2GND")
		(6 "In2.Cu" signal "L3")
		(8 "In3.Cu" signal "L4GND")
		(10 "In4.Cu" signal "L5")
		(12 "In5.Cu" signal "L6GND")
		(14 "In6.Cu" signal "L7VCC")
		(16 "In7.Cu" signal "L8VCC")
		(18 "In8.Cu" signal "L9GND")
		(20 "In9.Cu" signal "L10")
		(22 "In10.Cu" signal "L11GND")
		(24 "In11.Cu" signal "L12")
		(26 "In12.Cu" signal "L13GND")
		(2 "B.Cu" signal "BOTTOM")
		(9 "F.Adhes" user "F.Adhesive")
		(11 "B.Adhes" user "B.Adhesive")
		(13 "F.Paste" user "Package Geometry/Pastemask Top")
		(15 "B.Paste" user "Package Geometry/Pastemask Bottom")
		(5 "F.SilkS" user "Ref Des/Silkscreen Top")
		(7 "B.SilkS" user "Ref Des/Silkscreen Bottom")
		(1 "F.Mask" user "Board Geometry/Soldermask Top")
		(3 "B.Mask" user "Board Geometry/Soldermask Bottom")
		(17 "Dwgs.User" user "User.Drawings")
		(19 "Cmts.User" user "User.Comments")
		(21 "Eco1.User" user "User.Eco1")
		(23 "Eco2.User" user "User.Eco2")
		(25 "Edge.Cuts" user "Board Geometry/Outline")
		(27 "Margin" user)
		(31 "F.CrtYd" user "Package Geometry/Place Bound Top")
		(29 "B.CrtYd" user "Package Geometry/Place Bound Bottom")
		(35 "F.Fab" user "Ref Des/Assembly Top")
		(33 "B.Fab" user "Ref Des/Assembly Bottom")
	)
	(footprint ""
		(layer "F.Cu")
		(at 399.6182 1.7272 90)
		(property "Reference" "R8G23"
			(at 0 0 90)
			(layer "F.SilkS")
			(hide yes)
			(effects
				(font
					(size 1.27 1.27)
				)
			)
		)
		(property "Value" ""
			(at 0 0 90)
			(layer "F.Fab")
			(effects
				(font
					(size 1.27 1.27)
				)
			)
		)
		(duplicate_pad_numbers_are_jumpers no)
		(fp_poly
			(pts
				(xy -0.2794 -0.1016) (xy 0.2794 -0.1016) (xy 0.2794 0.9906) (xy -0.2794 0.9906)
			)
			(stroke
				(width 0)
				(type default)
			)
			(fill no)
			(layer "F.CrtYd")
		)
		(fp_line
			(start 0.2794 -0.1016)
			(end -0.2794 -0.1016)
			(stroke
				(width 0.1)
				(type default)
			)
			(layer "F.Fab")
		)
		(fp_line
			(start -0.2794 -0.1016)
			(end -0.2794 0.9906)
			(stroke
				(width 0.1)
				(type default)
			)
			(layer "F.Fab")
		)
		(fp_line
			(start 0.2794 0.9906)
			(end 0.2794 -0.1016)
			(stroke
				(width 0.1)
				(type default)
			)
			(layer "F.Fab")
		)
		(fp_line
			(start -0.2794 0.9906)
			(end 0.2794 0.9906)
			(stroke
				(width 0.1)
				(type default)
			)
			(layer "F.Fab")
		)
		(pad "1" smd rect
			(at 0 0 90)
			(size 0.508 0.508)
			(layers "F.Cu" "F.Mask" "F.Paste")
			(net "JTAG_TCK_R")
		)
		(pad "2" smd rect
			(at 0 0.889 90)
			(size 0.508 0.508)
			(layers "F.Cu" "F.Mask" "F.Paste")
			(net "GND")
		)
		(zone
			(layer "F.Cu")
			(hatch none 0.5)
			(connect_pads
				(clearance 0)
			)
			(min_thickness 0.25)
			(keepout
				(tracks allowed)
				(vias not_allowed)
				(pads allowed)
				(copperpour not_allowed)
				(footprints allowed)
			)
			(placement
				(enabled no)
				(sheetname "")
			)
			(fill
				(thermal_gap 0.5)
				(thermal_bridge_width 0.5)
				(island_removal_mode 0)
			)
			(polygon
				(pts
					(xy 399.8722 1.9812) (xy 399.8722 1.4732) (xy 400.2532 1.4732) (xy 400.2532 1.9812)
				)
			)
		)
		(zone
			(layer "F.Cu")
			(hatch none 0.5)
			(connect_pads
				(clearance 0)
			)
			(min_thickness 0.25)
			(keepout
				(tracks not_allowed)
				(vias allowed)
				(pads allowed)
				(copperpour not_allowed)
				(footprints allowed)
			)
			(placement
				(enabled no)
				(sheetname "")
			)
			(fill
				(thermal_gap 0.5)
				(thermal_bridge_width 0.5)
				(island_removal_mode 0)
			)
			(polygon
				(pts
					(xy 400.2532 1.9812) (xy 400.2532 1.4732) (xy 399.8722 1.4732) (xy 399.8722 1.9812)
				)
			)
		)
	)
	(footprint ""
		(layer "F.Cu")
		(at 155.6512 -118.364 90)
		(property "Reference" "R3B5"
			(at 0 0 90)
			(layer "F.SilkS")
			(hide yes)
			(effects
				(font
					(size 1.27 1.27)
				)
			)
		)
		(property "Value" ""
			(at 0 0 90)
			(layer "F.Fab")
			(effects
				(font
					(size 1.27 1.27)
				)
			)
		)
		(duplicate_pad_numbers_are_jumpers no)
		(fp_poly
			(pts
				(xy -0.2794 -0.1016) (xy 0.2794 -0.1016) (xy 0.2794 0.9906) (xy -0.2794 0.9906)
			)
			(stroke
				(width 0)
				(type default)
			)
			(fill no)
			(layer "F.CrtYd")
		)
		(fp_line
			(start 0.2794 -0.1016)
			(end -0.2794 -0.1016)
			(stroke
				(width 0.1)
				(type default)
			)
			(layer "F.Fab")
		)
		(fp_line
			(start -0.2794 -0.1016)
			(end -0.2794 0.9906)
			(stroke
				(width 0.1)
				(type default)
			)
			(layer "F.Fab")
		)
		(fp_line
			(start 0.2794 0.9906)
			(end 0.2794 -0.1016)
			(stroke
				(width 0.1)
				(type default)
			)
			(layer "F.Fab")
		)
		(fp_line
			(start -0.2794 0.9906)
			(end 0.2794 0.9906)
			(stroke
				(width 0.1)
				(type default)
			)
			(layer "F.Fab")
		)
		(pad "1" smd rect
			(at 0 0 90)
			(size 0.508 0.508)
			(layers "F.Cu" "F.Mask" "F.Paste")
			(net "SVID_CLK0_CPU1")
		)
		(pad "2" smd rect
			(at 0 0.889 90)
			(size 0.508 0.508)
			(layers "F.Cu" "F.Mask" "F.Paste")
			(net "SVID_CLK0_CPU1_R")
		)
		(zone
			(layer "F.Cu")
			(hatch none 0.5)
			(connect_pads
				(clearance 0)
			)
			(min_thickness 0.25)
			(keepout
				(tracks allowed)
				(vias not_allowed)
				(pads allowed)
				(copperpour not_allowed)
				(footprints allowed)
			)
			(placement
				(enabled no)
				(sheetname "")
			)
			(fill
				(thermal_gap 0.5)
				(thermal_bridge_width 0.5)
				(island_removal_mode 0)
			)
			(polygon
				(pts
					(xy 155.9052 -118.11) (xy 155.9052 -118.618) (xy 156.2862 -118.618) (xy 156.2862 -118.11)
				)
			)
		)
		(zone
			(layer "F.Cu")
			(hatch none 0.5)
			(connect_pads
				(clearance 0)
			)
			(min_thickness 0.25)
			(keepout
				(tracks not_allowed)
				(vias allowed)
				(pads allowed)
				(copperpour not_allowed)
				(footprints allowed)
			)
			(placement
				(enabled no)
				(sheetname "")
			)
			(fill
				(thermal_gap 0.5)
				(thermal_bridge_width 0.5)
				(island_removal_mode 0)
			)
			(polygon
				(pts
					(xy 156.2862 -118.11) (xy 156.2862 -118.618) (xy 155.9052 -118.618) (xy 155.9052 -118.11)
				)
			)
		)
	)
	(footprint ""
		(layer "F.Cu")
		(at 21.863812 -68.6943)
		(property "Reference" "C1W16"
			(at -0.8382 -0.67818 0)
			(unlocked yes)
			(layer "F.SilkS")
			(effects
				(font
					(size 0.4064 0.254)
					(thickness 0.1524)
				)
				(justify left)
			)
		)
		(property "Value" ""
			(at 0 0 0)
			(layer "F.Fab")
			(effects
				(font
					(size 1.27 1.27)
				)
			)
		)
		(duplicate_pad_numbers_are_jumpers no)
		(fp_poly
			(pts
				(xy 0.3048 -0.1016) (xy 0.3048 0.9906) (xy -0.3048 0.9906) (xy -0.3048 -0.1016)
			)
			(stroke
				(width 0)
				(type default)
			)
			(fill no)
			(layer "F.CrtYd")
		)
		(fp_line
			(start -0.3048 -0.1016)
			(end -0.3048 0.9906)
			(stroke
				(width 0.1)
				(type default)
			)
			(layer "F.Fab")
		)
		(fp_line
			(start -0.3048 0.9906)
			(end 0.3048 0.9906)
			(stroke
				(width 0.1)
				(type default)
			)
			(layer "F.Fab")
		)
		(fp_line
			(start 0.3048 -0.1016)
			(end -0.3048 -0.1016)
			(stroke
				(width 0.1)
				(type default)
			)
			(layer "F.Fab")
		)
		(fp_line
			(start 0.3048 0.9906)
			(end 0.3048 -0.1016)
			(stroke
				(width 0.1)
				(type default)
			)
			(layer "F.Fab")
		)
		(pad "1" smd rect
			(at 0 0)
			(size 0.508 0.508)
			(layers "F.Cu" "F.Mask" "F.Paste")
			(net "A_HSC_TEMP")
		)
		(pad "2" smd rect
			(at 0 0.889)
			(size 0.508 0.508)
			(layers "F.Cu" "F.Mask" "F.Paste")
			(net "GND")
		)
		(zone
			(layer "F.Cu")
			(hatch none 0.5)
			(connect_pads
				(clearance 0)
			)
			(min_thickness 0.25)
			(keepout
				(tracks allowed)
				(vias not_allowed)
				(pads allowed)
				(copperpour not_allowed)
				(footprints allowed)
			)
			(placement
				(enabled no)
				(sheetname "")
			)
			(fill
				(thermal_gap 0.5)
				(thermal_bridge_width 0.5)
				(island_removal_mode 0)
			)
			(polygon
				(pts
					(xy 21.609812 -68.4403) (xy 22.117812 -68.4403) (xy 22.117812 -68.0593) (xy 21.609812 -68.0593)
				)
			)
		)
		(zone
			(layer "F.Cu")
			(hatch none 0.5)
			(connect_pads
				(clearance 0)
			)
			(min_thickness 0.25)
			(keepout
				(tracks not_allowed)
				(vias allowed)
				(pads allowed)
				(copperpour not_allowed)
				(footprints allowed)
			)
			(placement
				(enabled no)
				(sheetname "")
			)
			(fill
				(thermal_gap 0.5)
				(thermal_bridge_width 0.5)
				(island_removal_mode 0)
			)
			(polygon
				(pts
					(xy 21.609812 -68.0593) (xy 22.117812 -68.0593) (xy 22.117812 -68.4403) (xy 21.609812 -68.4403)
				)
			)
		)
	)
)
